(kicad_pcb
	(version 20260206)
	(generator "pcbnew")
	(generator_version "10.0")
	(general
		(thickness 1.6)
		(legacy_teardrops no)
	)
	(paper "A4")
	(title_block
		(title "fcb — 12433-1M.1206WZS1330.brd")
		(comment 1 "Open Vault / Knox (Wiwynn) / footprints 302-308 of 495")
	)
	(layers
		(0 "F.Cu" signal "TOP")
		(4 "In1.Cu" signal "L2GND")
		(6 "In2.Cu" signal "L3VCC")
		(2 "B.Cu" signal "BOTTOM")
		(9 "F.Adhes" user "F.Adhesive")
		(11 "B.Adhes" user "B.Adhesive")
		(13 "F.Paste" user "Package Geometry/Pastemask Top")
		(15 "B.Paste" user "Package Geometry/Pastemask Bottom")
		(5 "F.SilkS" user "Ref Des/Silkscreen Top")
		(7 "B.SilkS" user "Ref Des/Silkscreen Bottom")
		(1 "F.Mask" user "Board Geometry/Soldermask Top")
		(3 "B.Mask" user "Board Geometry/Soldermask Bottom")
		(17 "Dwgs.User" user "User.Drawings")
		(19 "Cmts.User" user "User.Comments")
		(21 "Eco1.User" user "User.Eco1")
		(23 "Eco2.User" user "User.Eco2")
		(25 "Edge.Cuts" user "Board Geometry/Outline")
		(27 "Margin" user)
		(31 "F.CrtYd" user "Package Geometry/Place Bound Top")
		(29 "B.CrtYd" user "Package Geometry/Place Bound Bottom")
		(35 "F.Fab" user "Ref Des/Assembly Top")
		(33 "B.Fab" user "Ref Des/Assembly Bottom")
	)
	(footprint ""
		(layer "F.Cu")
		(at 26.227024 -173.96841 90)
		(property "Reference" "U2"
			(at 0 0 90)
			(layer "F.SilkS")
			(hide yes)
			(effects
				(font
					(size 1.27 1.27)
				)
			)
		)
		(property "Value" "NCT7368S-GP"
			(at 3.8989 1.5748 90)
			(unlocked yes)
			(layer "F.Fab")
			(hide yes)
			(effects
				(font
					(size 1.016 1.016)
					(thickness 0.1524)
				)
			)
		)
		(property "Device Type" "SOIC8-G3627H69"
			(at 3.8989 0.0508 90)
			(unlocked yes)
			(layer "F.Fab")
			(hide yes)
			(effects
				(font
					(size 1.016 1.016)
					(thickness 0.1524)
				)
			)
		)
		(duplicate_pad_numbers_are_jumpers no)
		(fp_line
			(start 2.7178 -3.6322)
			(end 2.7178 3.6322)
			(stroke
				(width 0.1524)
				(type default)
			)
			(layer "F.SilkS")
		)
		(fp_line
			(start -2.8829 -3.6322)
			(end 2.7178 -3.6322)
			(stroke
				(width 0.1524)
				(type default)
			)
			(layer "F.SilkS")
		)
		(fp_line
			(start -2.8829 -0.6223)
			(end -2.2479 0.0127)
			(stroke
				(width 0.1524)
				(type default)
			)
			(layer "F.SilkS")
		)
		(fp_line
			(start -2.2479 0.0127)
			(end -2.8829 0.6477)
			(stroke
				(width 0.1524)
				(type default)
			)
			(layer "F.SilkS")
		)
		(fp_line
			(start -2.8829 0.6477)
			(end -2.8829 -0.6223)
			(stroke
				(width 0.1524)
				(type default)
			)
			(layer "F.SilkS")
		)
		(fp_line
			(start 2.7178 3.6322)
			(end -2.8829 3.6322)
			(stroke
				(width 0.1524)
				(type default)
			)
			(layer "F.SilkS")
		)
		(fp_line
			(start -2.7051 3.6322)
			(end -2.7051 1.5494)
			(stroke
				(width 0.508)
				(type default)
			)
			(layer "F.SilkS")
		)
		(fp_line
			(start -2.8829 3.6322)
			(end -2.8829 -3.6322)
			(stroke
				(width 0.1524)
				(type default)
			)
			(layer "F.SilkS")
		)
		(fp_poly
			(pts
				(xy 0.2794 -0.2794) (xy 1.8034 -0.2794) (xy 1.8034 -1.3462) (xy 0.2794 -1.3462)
			)
			(stroke
				(width 0)
				(type default)
			)
			(fill yes)
			(layer "F.Paste")
		)
		(fp_poly
			(pts
				(xy -1.8034 -0.2794) (xy -0.2794 -0.2794) (xy -0.2794 -1.3462) (xy -1.8034 -1.3462)
			)
			(stroke
				(width 0)
				(type default)
			)
			(fill yes)
			(layer "F.Paste")
		)
		(fp_poly
			(pts
				(xy 0.2794 1.3462) (xy 1.8034 1.3462) (xy 1.8034 0.2794) (xy 0.2794 0.2794)
			)
			(stroke
				(width 0)
				(type default)
			)
			(fill yes)
			(layer "F.Paste")
		)
		(fp_poly
			(pts
				(xy -1.8034 1.3462) (xy -0.2794 1.3462) (xy -0.2794 0.2794) (xy -1.8034 0.2794)
			)
			(stroke
				(width 0)
				(type default)
			)
			(fill yes)
			(layer "F.Paste")
		)
		(fp_poly
			(pts
				(xy -2.1209 2.9972) (xy -2.1209 1.9558) (xy -2.4511 1.9558) (xy -2.4511 -1.9558) (xy -2.1209 -1.9558)
				(xy -2.1209 -2.9972) (xy 2.1209 -2.9972) (xy 2.1209 -1.9558) (xy 2.4511 -1.9558) (xy 2.4511 1.9558)
				(xy 2.1209 1.9558) (xy 2.1209 2.9972)
			)
			(stroke
				(width 0)
				(type default)
			)
			(fill no)
			(layer "F.CrtYd")
		)
		(fp_poly
			(pts
				(xy -2.9591 3.8862) (xy -2.9591 -3.8862) (xy 2.9591 -3.8862) (xy 2.9591 1.95072) (xy 2.4511 1.95072)
				(xy 2.4511 -1.9558) (xy 2.1209 -1.9558) (xy 2.1209 -2.9972) (xy -2.1209 -2.9972) (xy -2.1209 -1.9558)
				(xy -2.4511 -1.9558) (xy -2.4511 1.9558) (xy -2.1209 1.9558) (xy -2.1209 2.9972) (xy 2.1209 2.9972)
				(xy 2.1209 1.9558) (xy 2.9591 1.9558) (xy 2.9591 3.8862)
			)
			(stroke
				(width 0)
				(type default)
			)
			(fill no)
			(layer "F.CrtYd")
		)
		(fp_rect
			(start -2.9591 3.8862)
			(end 2.9591 -3.8862)
			(stroke
				(width 0)
				(type default)
			)
			(fill no)
			(layer "F.Fab")
		)
		(pad "1" smd rect
			(at -1.905 2.5527 90)
			(size 0.635 1.651)
			(layers "F.Cu" "F.Mask" "F.Paste")
			(net "P3V3")
		)
		(pad "2" smd rect
			(at -0.635 2.5527 90)
			(size 0.635 1.651)
			(layers "F.Cu" "F.Mask" "F.Paste")
			(net "PWM_EXP_1A")
		)
		(pad "3" smd rect
			(at 0.635 2.5527 90)
			(size 0.635 1.651)
			(layers "F.Cu" "F.Mask" "F.Paste")
			(net "PWM_EXP_1B")
		)
		(pad "4" smd rect
			(at 1.905 2.5527 90)
			(size 0.635 1.651)
			(layers "F.Cu" "F.Mask" "F.Paste")
			(net "PWM_EXP_2A")
		)
		(pad "5" smd rect
			(at 1.905 -2.5527 90)
			(size 0.635 1.651)
			(layers "F.Cu" "F.Mask" "F.Paste")
			(net "NCT7368S_SEL")
		)
		(pad "6" smd rect
			(at 0.635 -2.5527 90)
			(size 0.635 1.651)
			(layers "F.Cu" "F.Mask" "F.Paste")
			(net "THERMHOT#")
		)
		(pad "7" smd rect
			(at -0.635 -2.5527 90)
			(size 0.635 1.651)
			(layers "F.Cu" "F.Mask" "F.Paste")
			(net "PWM_OUT")
		)
		(pad "8" smd rect
			(at -1.905 -2.5527 90)
			(size 0.635 1.651)
			(layers "F.Cu" "F.Mask" "F.Paste")
			(net "PWM_EXP_2B")
		)
		(pad "9" smd rect
			(at 0 0 90)
			(size 3.6068 2.6924)
			(layers "F.Cu" "F.Mask" "F.Paste")
			(net "GND")
		)
	)
	(footprint ""
		(layer "F.Cu")
		(at 13.1318 -150.622 90)
		(property "Reference" "D2"
			(at 0 0 90)
			(layer "F.SilkS")
			(hide yes)
			(effects
				(font
					(size 1.27 1.27)
				)
			)
		)
		(property "Value" "BAS16H-GP"
			(at 0 -5.5372 90)
			(unlocked yes)
			(layer "F.Fab")
			(hide yes)
			(effects
				(font
					(size 1.016 1.016)
					(thickness 0.1524)
				)
			)
		)
		(property "Device Type" "SOD123AKH48"
			(at 0 -7.0612 90)
			(unlocked yes)
			(layer "F.Fab")
			(hide yes)
			(effects
				(font
					(size 1.016 1.016)
					(thickness 0.1524)
				)
			)
		)
		(duplicate_pad_numbers_are_jumpers no)
		(fp_line
			(start 1.016 -2.667)
			(end -1.016 -2.667)
			(stroke
				(width 0.1524)
				(type default)
			)
			(layer "F.SilkS")
		)
		(fp_line
			(start -1.016 -2.667)
			(end -1.016 2.667)
			(stroke
				(width 0.1524)
				(type default)
			)
			(layer "F.SilkS")
		)
		(fp_line
			(start 1.016 2.667)
			(end 1.016 -2.667)
			(stroke
				(width 0.1524)
				(type default)
			)
			(layer "F.SilkS")
		)
		(fp_line
			(start -1.016 2.667)
			(end 1.016 2.667)
			(stroke
				(width 0.1524)
				(type default)
			)
			(layer "F.SilkS")
		)
		(fp_line
			(start 0.889 2.921)
			(end -0.889 2.921)
			(stroke
				(width 0.508)
				(type default)
			)
			(layer "F.SilkS")
		)
		(fp_rect
			(start -1.143 3.175)
			(end 1.143 -2.794)
			(stroke
				(width 0)
				(type default)
			)
			(fill no)
			(layer "F.CrtYd")
		)
		(fp_poly
			(pts
				(xy -1.143 -2.794) (xy 1.143 -2.794) (xy 1.143 3.175) (xy -1.143 3.175)
			)
			(stroke
				(width 0)
				(type default)
			)
			(fill no)
			(layer "F.Fab")
		)
		(pad "A" smd rect
			(at 0 -1.6891 90)
			(size 0.889 1.397)
			(layers "F.Cu" "F.Mask" "F.Paste")
			(net "FAN_TACH10")
		)
		(pad "K" smd rect
			(at 0 1.6891 90)
			(size 0.889 1.397)
			(layers "F.Cu" "F.Mask" "F.Paste")
			(net "P12V")
		)
	)
	(footprint ""
		(layer "F.Cu")
		(at 6.604 -280.924 -90)
		(property "Reference" "R37"
			(at 0 0 270)
			(layer "F.SilkS")
			(hide yes)
			(effects
				(font
					(size 1.27 1.27)
				)
			)
		)
		(property "Value" "33R2F-3-GP"
			(at 0.064008 -3.993896 270)
			(unlocked yes)
			(layer "F.Fab")
			(hide yes)
			(effects
				(font
					(size 1.016 1.016)
					(thickness 0.1524)
				)
			)
		)
		(property "Device Type" "R402H16"
			(at 0.064008 -5.517896 270)
			(unlocked yes)
			(layer "F.Fab")
			(hide yes)
			(effects
				(font
					(size 1.016 1.016)
					(thickness 0.1524)
				)
			)
		)
		(duplicate_pad_numbers_are_jumpers no)
		(fp_line
			(start -0.508 -0.9398)
			(end -0.508 0.9398)
			(stroke
				(width 0.1524)
				(type default)
			)
			(layer "F.SilkS")
		)
		(fp_line
			(start 0.508 -0.9398)
			(end -0.508 -0.9398)
			(stroke
				(width 0.1524)
				(type default)
			)
			(layer "F.SilkS")
		)
		(fp_rect
			(start -0.508 0.9398)
			(end 0.508 -0.9398)
			(stroke
				(width 0)
				(type default)
			)
			(fill no)
			(layer "F.CrtYd")
		)
		(fp_rect
			(start -0.508 0.9398)
			(end 0.508 -0.9398)
			(stroke
				(width 0)
				(type default)
			)
			(fill no)
			(layer "F.Fab")
		)
		(pad "1" smd custom
			(at 0 -0.4445 270)
			(size 0.1397 0.1397)
			(layers "F.Cu" "F.Mask" "F.Paste")
			(net "P3V3")
			(options
				(clearance outline)
				(anchor circle)
			)
			(primitives
				(gr_poly
					(pts
						(arc
							(start -0.1778 -0.2794)
							(mid -0.249642 -0.249642)
							(end -0.2794 -0.1778)
						)
						(arc
							(start -0.2794 0.1778)
							(mid -0.249642 0.249642)
							(end -0.1778 0.2794)
						)
						(arc
							(start 0.1778 0.2794)
							(mid 0.249642 0.249642)
							(end 0.2794 0.1778)
						)
						(arc
							(start 0.2794 -0.1778)
							(mid 0.249642 -0.249642)
							(end 0.1778 -0.2794)
						)
					)
					(width 0)
					(fill yes)
				)
			)
		)
		(pad "2" smd custom
			(at 0 0.4445 270)
			(size 0.1397 0.1397)
			(layers "F.Cu" "F.Mask" "F.Paste")
			(net "LED_DR_LED2_BLUE")
			(options
				(clearance outline)
				(anchor circle)
			)
			(primitives
				(gr_poly
					(pts
						(arc
							(start -0.1778 -0.2794)
							(mid -0.249642 -0.249642)
							(end -0.2794 -0.1778)
						)
						(arc
							(start -0.2794 0.1778)
							(mid -0.249642 0.249642)
							(end -0.1778 0.2794)
						)
						(arc
							(start 0.1778 0.2794)
							(mid 0.249642 0.249642)
							(end 0.2794 0.1778)
						)
						(arc
							(start 0.2794 -0.1778)
							(mid 0.249642 -0.249642)
							(end 0.1778 -0.2794)
						)
					)
					(width 0)
					(fill yes)
				)
			)
		)
	)
	(footprint ""
		(layer "F.Cu")
		(at 37.973 -180.34)
		(property "Reference" "R261"
			(at 0 0 0)
			(layer "F.SilkS")
			(hide yes)
			(effects
				(font
					(size 1.27 1.27)
				)
			)
		)
		(property "Value" "10KR2J-3-GP"
			(at 0.064008 -3.993896 0)
			(unlocked yes)
			(layer "F.Fab")
			(hide yes)
			(effects
				(font
					(size 1.016 1.016)
					(thickness 0.1524)
				)
			)
		)
		(property "Device Type" "R402H16"
			(at 0.064008 -5.517896 0)
			(unlocked yes)
			(layer "F.Fab")
			(hide yes)
			(effects
				(font
					(size 1.016 1.016)
					(thickness 0.1524)
				)
			)
		)
		(duplicate_pad_numbers_are_jumpers no)
		(fp_line
			(start -0.508 -0.9398)
			(end -0.508 0.9398)
			(stroke
				(width 0.1524)
				(type default)
			)
			(layer "F.SilkS")
		)
		(fp_line
			(start 0.508 -0.9398)
			(end -0.508 -0.9398)
			(stroke
				(width 0.1524)
				(type default)
			)
			(layer "F.SilkS")
		)
		(fp_rect
			(start -0.508 0.9398)
			(end 0.508 -0.9398)
			(stroke
				(width 0)
				(type default)
			)
			(fill no)
			(layer "F.CrtYd")
		)
		(fp_rect
			(start -0.508 0.9398)
			(end 0.508 -0.9398)
			(stroke
				(width 0)
				(type default)
			)
			(fill no)
			(layer "F.Fab")
		)
		(pad "1" smd custom
			(at 0 -0.4445)
			(size 0.1397 0.1397)
			(layers "F.Cu" "F.Mask" "F.Paste")
			(net "D_LATCH_CLR")
			(options
				(clearance outline)
				(anchor circle)
			)
			(primitives
				(gr_poly
					(pts
						(arc
							(start -0.1778 -0.2794)
							(mid -0.249642 -0.249642)
							(end -0.2794 -0.1778)
						)
						(arc
							(start -0.2794 0.1778)
							(mid -0.249642 0.249642)
							(end -0.1778 0.2794)
						)
						(arc
							(start 0.1778 0.2794)
							(mid 0.249642 0.249642)
							(end 0.2794 0.1778)
						)
						(arc
							(start 0.2794 -0.1778)
							(mid 0.249642 -0.249642)
							(end 0.1778 -0.2794)
						)
					)
					(width 0)
					(fill yes)
				)
			)
		)
		(pad "2" smd custom
			(at 0 0.4445)
			(size 0.1397 0.1397)
			(layers "F.Cu" "F.Mask" "F.Paste")
			(net "P3V3_AUX")
			(options
				(clearance outline)
				(anchor circle)
			)
			(primitives
				(gr_poly
					(pts
						(arc
							(start -0.1778 -0.2794)
							(mid -0.249642 -0.249642)
							(end -0.2794 -0.1778)
						)
						(arc
							(start -0.2794 0.1778)
							(mid -0.249642 0.249642)
							(end -0.1778 0.2794)
						)
						(arc
							(start 0.1778 0.2794)
							(mid 0.249642 0.249642)
							(end 0.2794 0.1778)
						)
						(arc
							(start 0.2794 -0.1778)
							(mid 0.249642 -0.249642)
							(end 0.1778 -0.2794)
						)
					)
					(width 0)
					(fill yes)
				)
			)
		)
	)
	(footprint ""
		(layer "F.Cu")
		(at 26.543 -237.871)
		(property "Reference" "R154"
			(at 0 0 0)
			(layer "F.SilkS")
			(hide yes)
			(effects
				(font
					(size 1.27 1.27)
				)
			)
		)
		(property "Value" "0R0805-PAD-2-GP"
			(at 0.0508 -2.7432 0)
			(unlocked yes)
			(layer "F.Fab")
			(hide yes)
			(effects
				(font
					(size 1.016 1.016)
					(thickness 0.1524)
				)
			)
		)
		(property "Device Type" "0R0805-PAD-1"
			(at 0.0508 -4.2672 0)
			(unlocked yes)
			(layer "F.Fab")
			(hide yes)
			(effects
				(font
					(size 1.016 1.016)
					(thickness 0.1524)
				)
			)
		)
		(duplicate_pad_numbers_are_jumpers no)
		(fp_line
			(start -0.889 -1.7018)
			(end 0.889 -1.7018)
			(stroke
				(width 0.1524)
				(type default)
			)
			(layer "F.SilkS")
		)
		(fp_line
			(start -0.889 1.7018)
			(end -0.889 -1.7018)
			(stroke
				(width 0.1524)
				(type default)
			)
			(layer "F.SilkS")
		)
		(fp_line
			(start 0.889 -1.7018)
			(end 0.889 1.7018)
			(stroke
				(width 0.1524)
				(type default)
			)
			(layer "F.SilkS")
		)
		(fp_line
			(start 0.889 1.7018)
			(end -0.889 1.7018)
			(stroke
				(width 0.1524)
				(type default)
			)
			(layer "F.SilkS")
		)
		(fp_rect
			(start -0.9652 1.778)
			(end 0.9652 -1.778)
			(stroke
				(width 0)
				(type default)
			)
			(fill no)
			(layer "F.CrtYd")
		)
		(fp_rect
			(start -0.9652 1.778)
			(end 0.9652 -1.778)
			(stroke
				(width 0)
				(type default)
			)
			(fill no)
			(layer "F.Fab")
		)
		(pad "1" smd rect
			(at 0 -0.9652)
			(size 1.397 1.5621)
			(drill
				(offset 0 0.20955)
			)
			(layers "F.Cu" "F.Mask" "F.Paste")
			(net "P3V3_LX_COPPER")
		)
		(pad "2" smd rect
			(at 0 0.9652)
			(size 1.397 1.568704)
			(drill
				(offset 0 -0.206248)
			)
			(layers "F.Cu" "F.Mask" "F.Paste")
			(net "P3V3")
		)
	)
	(footprint ""
		(layer "F.Cu")
		(at 18.644362 -157.505908 90)
		(property "Reference" "F2"
			(at 0 0 90)
			(layer "F.SilkS")
			(hide yes)
			(effects
				(font
					(size 1.27 1.27)
				)
			)
		)
		(property "Value" "FUSE-3A15V-GP"
			(at 0.2286 -10.5918 90)
			(unlocked yes)
			(layer "F.Fab")
			(hide yes)
			(effects
				(font
					(size 1.016 1.016)
					(thickness 0.1524)
				)
			)
		)
		(property "Device Type" "FUSE-7452-UH50"
			(at 0.2286 -12.4968 90)
			(unlocked yes)
			(layer "F.Fab")
			(hide yes)
			(effects
				(font
					(size 1.016 1.016)
					(thickness 0.1524)
				)
			)
		)
		(duplicate_pad_numbers_are_jumpers no)
		(fp_line
			(start 4.9276 -2.921)
			(end 4.9276 2.921)
			(stroke
				(width 0.1524)
				(type default)
			)
			(layer "F.SilkS")
		)
		(fp_line
			(start -4.9276 -2.921)
			(end 4.9276 -2.921)
			(stroke
				(width 0.1524)
				(type default)
			)
			(layer "F.SilkS")
		)
		(fp_line
			(start 4.9276 2.921)
			(end -4.9276 2.921)
			(stroke
				(width 0.1524)
				(type default)
			)
			(layer "F.SilkS")
		)
		(fp_line
			(start -4.9276 2.921)
			(end -4.9276 -2.921)
			(stroke
				(width 0.1524)
				(type default)
			)
			(layer "F.SilkS")
		)
		(fp_poly
			(pts
				(xy -5.08 3.0988) (xy 5.08 3.0988) (xy 5.08 -3.0988) (xy -5.08 -3.0988)
			)
			(stroke
				(width 0)
				(type default)
			)
			(fill no)
			(layer "F.CrtYd")
		)
		(fp_poly
			(pts
				(xy -5.08 -3.0988) (xy 5.08 -3.0988) (xy 5.08 3.0988) (xy -5.08 3.0988)
			)
			(stroke
				(width 0)
				(type default)
			)
			(fill no)
			(layer "F.Fab")
		)
		(pad "1" smd rect
			(at -3.4036 0 90)
			(size 2.2098 5.2832)
			(layers "F.Cu" "F.Mask" "F.Paste")
			(net "P12V_FAN5")
		)
		(pad "2" smd rect
			(at 3.4036 0 90)
			(size 2.2098 5.2832)
			(layers "F.Cu" "F.Mask" "F.Paste")
			(net "P12V")
		)
	)
	(footprint ""
		(layer "F.Cu")
		(at 31.75 -381 180)
		(property "Reference" "PR21"
			(at 0 0 180)
			(layer "F.SilkS")
			(hide yes)
			(effects
				(font
					(size 1.27 1.27)
				)
			)
		)
		(property "Value" "10R2F-L-GP"
			(at 0.064008 -3.993896 180)
			(unlocked yes)
			(layer "F.Fab")
			(hide yes)
			(effects
				(font
					(size 1.016 1.016)
					(thickness 0.1524)
				)
			)
		)
		(property "Device Type" "R402H14"
			(at 0.064008 -5.517896 180)
			(unlocked yes)
			(layer "F.Fab")
			(hide yes)
			(effects
				(font
					(size 1.016 1.016)
					(thickness 0.1524)
				)
			)
		)
		(duplicate_pad_numbers_are_jumpers no)
		(fp_line
			(start 0.508 -0.9398)
			(end -0.508 -0.9398)
			(stroke
				(width 0.1524)
				(type default)
			)
			(layer "F.SilkS")
		)
		(fp_line
			(start -0.508 -0.9398)
			(end -0.508 0.9398)
			(stroke
				(width 0.1524)
				(type default)
			)
			(layer "F.SilkS")
		)
		(fp_rect
			(start -0.508 0.9398)
			(end 0.508 -0.9398)
			(stroke
				(width 0)
				(type default)
			)
			(fill no)
			(layer "F.CrtYd")
		)
		(fp_rect
			(start -0.508 0.9398)
			(end 0.508 -0.9398)
			(stroke
				(width 0)
				(type default)
			)
			(fill no)
			(layer "F.Fab")
		)
		(pad "1" smd custom
			(at 0 -0.4445 180)
			(size 0.1397 0.1397)
			(layers "F.Cu" "F.Mask" "F.Paste")
			(net "ADM1276_SENSE-")
			(options
				(clearance outline)
				(anchor circle)
			)
			(primitives
				(gr_poly
					(pts
						(arc
							(start -0.1778 -0.2794)
							(mid -0.249642 -0.249642)
							(end -0.2794 -0.1778)
						)
						(arc
							(start -0.2794 0.1778)
							(mid -0.249642 0.249642)
							(end -0.1778 0.2794)
						)
						(arc
							(start 0.1778 0.2794)
							(mid 0.249642 0.249642)
							(end 0.2794 0.1778)
						)
						(arc
							(start 0.2794 -0.1778)
							(mid 0.249642 -0.249642)
							(end 0.1778 -0.2794)
						)
					)
					(width 0)
					(fill yes)
				)
			)
		)
		(pad "2" smd custom
			(at 0 0.4445 180)
			(size 0.1397 0.1397)
			(layers "F.Cu" "F.Mask" "F.Paste")
			(net "SENSE-_R1")
			(options
				(clearance outline)
				(anchor circle)
			)
			(primitives
				(gr_poly
					(pts
						(arc
							(start -0.1778 -0.2794)
							(mid -0.249642 -0.249642)
							(end -0.2794 -0.1778)
						)
						(arc
							(start -0.2794 0.1778)
							(mid -0.249642 0.249642)
							(end -0.1778 0.2794)
						)
						(arc
							(start 0.1778 0.2794)
							(mid 0.249642 0.249642)
							(end 0.2794 0.1778)
						)
						(arc
							(start 0.2794 -0.1778)
							(mid 0.249642 -0.249642)
							(end 0.1778 -0.2794)
						)
					)
					(width 0)
					(fill yes)
				)
			)
		)
	)
)
